# T6G (Grand Teton) — schematic netlist excerpt (pin names and nets, part order shuffled) for the footprints in the layout excerpt that follows; sources: Cadence DE-HDL packaged netlist, KiCad conversion of 04192023_DAF0TMB3IC0_F0TG_MB_C_brd_V02_OCP.brd

U264  ISL28022FRZT  ISL28022FRZ-T IC  pkg QFN16_TH_0-5_3X3XH  page 237
  A1  = INA230_4_A1
  A0  = INA230_4_A0
  \ext_clk||int\  = M2_0_P3V3_ADC_ALERT_R
  \sda||smbdat\  = SMB_INA230_4_3V3AUX_SDA_R1
  \scl|||smbclk\  = SMB_INA230_4_3V3AUX_SCL_R1
  NC0  = NC_INA230_4_NC0
  NC1  = NC_INA230_4_NC1
  NC2  = NC_INA230_4_NC2
  VCC  = P3V3_AUX
  GND  = GND
  VBUS  = P3V3
  VINM  = VSENSE_P12V_INA230_4_INN
  VINP  = VSENSE_P12V_INA230_4_INP
  NC3  = NC_INA230_4_NC3
  NC4  = NC_INA230_4_NC4
  NC5  = NC_INA230_4_NC5
  TH_GND  = GND

(kicad_pcb
	(version 20260206)
	(generator "pcbnew")
	(generator_version "10.0")
	(general
		(thickness 1.6)
		(legacy_teardrops no)
	)
	(paper "A4")
	(title_block
		(title "04192023_DAF0TMB3IC0_F0TG_MB_C_brd_V02_OCP.brd")
		(comment 1 "Grand Teton / footprints 3010-3010 of 8354")
	)
	(layers
		(0 "F.Cu" signal "TOP")
		(4 "In1.Cu" signal "GND")
		(6 "In2.Cu" signal "IN1")
		(8 "In3.Cu" signal "GND1")
		(10 "In4.Cu" signal "IN2")
		(12 "In5.Cu" signal "GND2")
		(14 "In6.Cu" signal "IN3")
		(16 "In7.Cu" signal "GND3")
		(18 "In8.Cu" signal "VCC")
		(20 "In9.Cu" signal "VCC1")
		(22 "In10.Cu" signal "GND4")
		(24 "In11.Cu" signal "IN4")
		(26 "In12.Cu" signal "GND5")
		(28 "In13.Cu" signal "IN5")
		(30 "In14.Cu" signal "GND6")
		(32 "In15.Cu" signal "IN6")
		(34 "In16.Cu" signal "GND7")
		(2 "B.Cu" signal "BOTTOM")
		(9 "F.Adhes" user "F.Adhesive")
		(11 "B.Adhes" user "B.Adhesive")
		(13 "F.Paste" user "Package Geometry/Pastemask Top")
		(15 "B.Paste" user "Package Geometry/Pastemask Bottom")
		(5 "F.SilkS" user "Ref Des/Silkscreen Top")
		(7 "B.SilkS" user "Ref Des/Silkscreen Bottom")
		(1 "F.Mask" user "Board Geometry/Soldermask Top")
		(3 "B.Mask" user "Board Geometry/Soldermask Bottom")
		(17 "Dwgs.User" user "User.Drawings")
		(19 "Cmts.User" user "User.Comments")
		(21 "Eco1.User" user "User.Eco1")
		(23 "Eco2.User" user "User.Eco2")
		(25 "Edge.Cuts" user "Board Geometry/Outline")
		(27 "Margin" user)
		(31 "F.CrtYd" user "Package Geometry/Place Bound Top")
		(29 "B.CrtYd" user "Package Geometry/Place Bound Bottom")
		(35 "F.Fab" user "Ref Des/Assembly Top")
		(33 "B.Fab" user "Ref Des/Assembly Bottom")
	)
	(footprint ""
		(layer "F.Cu")
		(at 154.998166 -57.118758)
		(property "Reference" "U264"
			(at 4.994656 -3.027426 0)
			(unlocked yes)
			(layer "F.SilkS")
			(effects
				(font
					(size 0.7874 0.5842)
					(thickness 0.1524)
				)
			)
		)
		(property "Value" ""
			(at 0 0 0)
			(layer "F.Fab")
			(effects
				(font
					(size 1.27 1.27)
				)
			)
		)
		(duplicate_pad_numbers_are_jumpers no)
		(fp_line
			(start -1.500124 -1.500124)
			(end -1.004062 -1.500124)
			(stroke
				(width 0.1524)
				(type default)
			)
			(layer "F.SilkS")
		)
		(fp_line
			(start -1.500124 -1.004062)
			(end -1.500124 -1.500124)
			(stroke
				(width 0.1524)
				(type default)
			)
			(layer "F.SilkS")
		)
		(fp_line
			(start -1.500124 1.500124)
			(end -1.500124 1.004062)
			(stroke
				(width 0.1524)
				(type default)
			)
			(layer "F.SilkS")
		)
		(fp_line
			(start -1.004062 1.500124)
			(end -1.500124 1.500124)
			(stroke
				(width 0.1524)
				(type default)
			)
			(layer "F.SilkS")
		)
		(fp_line
			(start 1.004062 -1.500124)
			(end 1.500124 -1.500124)
			(stroke
				(width 0.1524)
				(type default)
			)
			(layer "F.SilkS")
		)
		(fp_line
			(start 1.500124 -1.500124)
			(end 1.500124 -1.004062)
			(stroke
				(width 0.1524)
				(type default)
			)
			(layer "F.SilkS")
		)
		(fp_line
			(start 1.500124 1.004062)
			(end 1.500124 1.500124)
			(stroke
				(width 0.1524)
				(type default)
			)
			(layer "F.SilkS")
		)
		(fp_line
			(start 1.500124 1.500124)
			(end 1.004062 1.500124)
			(stroke
				(width 0.1524)
				(type default)
			)
			(layer "F.SilkS")
		)
		(fp_poly
			(pts
				(xy -3.570986 -0.960882) (xy -3.08737 -1.854454) (xy -2.435606 -0.924306)
			)
			(stroke
				(width 0)
				(type default)
			)
			(fill yes)
			(layer "F.SilkS")
		)
		(fp_line
			(start -1.500124 -1.500124)
			(end 1.500124 -1.500124)
			(stroke
				(width 0.1)
				(type default)
			)
			(layer "F.Fab")
		)
		(fp_line
			(start -1.500124 1.500124)
			(end -1.500124 -1.500124)
			(stroke
				(width 0.1)
				(type default)
			)
			(layer "F.Fab")
		)
		(fp_line
			(start 1.500124 -1.500124)
			(end 1.500124 1.500124)
			(stroke
				(width 0.1)
				(type default)
			)
			(layer "F.Fab")
		)
		(fp_line
			(start 1.500124 1.500124)
			(end -1.500124 1.500124)
			(stroke
				(width 0.1)
				(type default)
			)
			(layer "F.Fab")
		)
		(fp_poly
			(pts
				(xy -2.847848 -1.258062) (xy -2.847848 -0.242062) (xy -1.831848 -0.750062)
			)
			(stroke
				(width 0)
				(type default)
			)
			(fill yes)
			(layer "F.Fab")
		)
		(pad "1" smd rect
			(at -1.400048 -0.750062 270)
			(size 0.2286 0.6096)
			(layers "F.Cu" "F.Mask" "F.Paste")
			(net "INA230_4_A1")
		)
		(pad "2" smd rect
			(at -1.400048 -0.249936 270)
			(size 0.2286 0.6096)
			(layers "F.Cu" "F.Mask" "F.Paste")
			(net "INA230_4_A0")
		)
		(pad "3" smd rect
			(at -1.400048 0.249936 270)
			(size 0.2286 0.6096)
			(layers "F.Cu" "F.Mask" "F.Paste")
			(net "M2_0_P3V3_ADC_ALERT_R")
		)
		(pad "4" smd rect
			(at -1.400048 0.750062 270)
			(size 0.2286 0.6096)
			(layers "F.Cu" "F.Mask" "F.Paste")
			(net "SMB_INA230_4_3V3AUX_SDA_R1")
		)
		(pad "5" smd rect
			(at -0.750062 1.400048)
			(size 0.2286 0.6096)
			(layers "F.Cu" "F.Mask" "F.Paste")
			(net "SMB_INA230_4_3V3AUX_SCL_R1")
		)
		(pad "6" smd rect
			(at -0.249936 1.400048)
			(size 0.2286 0.6096)
			(layers "F.Cu" "F.Mask" "F.Paste")
			(net "NC_INA230_4_NC0")
		)
		(pad "7" smd rect
			(at 0.249936 1.400048)
			(size 0.2286 0.6096)
			(layers "F.Cu" "F.Mask" "F.Paste")
			(net "NC_INA230_4_NC1")
		)
		(pad "8" smd rect
			(at 0.750062 1.400048)
			(size 0.2286 0.6096)
			(layers "F.Cu" "F.Mask" "F.Paste")
			(net "NC_INA230_4_NC2")
		)
		(pad "9" smd rect
			(at 1.400048 0.750062 270)
			(size 0.2286 0.6096)
			(layers "F.Cu" "F.Mask" "F.Paste")
			(net "P3V3_AUX")
		)
		(pad "10" smd rect
			(at 1.400048 0.249936 270)
			(size 0.2286 0.6096)
			(layers "F.Cu" "F.Mask" "F.Paste")
			(net "GND")
		)
		(pad "11" smd rect
			(at 1.400048 -0.249936 270)
			(size 0.2286 0.6096)
			(layers "F.Cu" "F.Mask" "F.Paste")
			(net "P3V3")
		)
		(pad "12" smd rect
			(at 1.400048 -0.750062 270)
			(size 0.2286 0.6096)
			(layers "F.Cu" "F.Mask" "F.Paste")
			(net "VSENSE_P12V_INA230_4_INN")
		)
		(pad "13" smd rect
			(at 0.750062 -1.400048)
			(size 0.2286 0.6096)
			(layers "F.Cu" "F.Mask" "F.Paste")
			(net "VSENSE_P12V_INA230_4_INP")
		)
		(pad "14" smd rect
			(at 0.249936 -1.400048)
			(size 0.2286 0.6096)
			(layers "F.Cu" "F.Mask" "F.Paste")
			(net "NC_INA230_4_NC3")
		)
		(pad "15" smd rect
			(at -0.249936 -1.400048)
			(size 0.2286 0.6096)
			(layers "F.Cu" "F.Mask" "F.Paste")
			(net "NC_INA230_4_NC4")
		)
		(pad "16" smd rect
			(at -0.750062 -1.400048)
			(size 0.2286 0.6096)
			(layers "F.Cu" "F.Mask" "F.Paste")
			(net "NC_INA230_4_NC5")
		)
		(pad "TH" smd rect
			(at 0 0)
			(size 1.7018 1.7018)
			(layers "F.Cu" "F.Mask" "F.Paste")
			(net "GND")
		)
		(zone
			(layer "F.Cu")
			(hatch none 0.5)
			(connect_pads
				(clearance 0)
			)
			(min_thickness 0.25)
			(keepout
				(tracks not_allowed)
				(vias allowed)
				(pads allowed)
				(copperpour not_allowed)
				(footprints allowed)
			)
			(placement
				(enabled no)
				(sheetname "")
			)
			(fill
				(thermal_gap 0.5)
				(thermal_bridge_width 0.5)
				(island_removal_mode 0)
			)
			(polygon
				(pts
					(xy 153.953718 -57.118758) (xy 154.096466 -57.118758) (xy 154.096466 -56.217058) (xy 155.899866 -56.217058)
					(xy 155.899866 -56.64454) (xy 156.042614 -56.64454) (xy 156.042614 -56.07431) (xy 153.953718 -56.07431)
				)
			)
		)
	)
)
